# T6G (Grand Teton) — schematic netlist excerpt (pin names and nets, part order shuffled) for the footprints in the layout excerpt that follows; sources: Cadence DE-HDL packaged netlist, KiCad conversion of 04192023_DAF0TMB3IC0_F0TG_MB_C_brd_V02_OCP.brd

PC11  Q_CAP  0.1UF 25V 10% X7R  pkg 0402  page 210 : A = PVDDCR_CPU0_P1_VCCS ; B = GND
C2669  Q_CAP  22UF 4V 20% X6S  pkg C0402  page 75 : A = PVDD18_S5_P1 ; B = GND
PC559_4  Q_CAP  22UF 16V 20% X6S  pkg C0805  page 195 : A = SW_P12V_AUX_PVDDCR_CPU0_P0_FLT ; B = GND

(kicad_pcb
	(version 20260206)
	(generator "pcbnew")
	(generator_version "10.0")
	(general
		(thickness 1.6)
		(legacy_teardrops no)
	)
	(paper "A4")
	(title_block
		(title "04192023_DAF0TMB3IC0_F0TG_MB_C_brd_V02_OCP.brd")
		(comment 1 "Grand Teton / footprints 4959-4961 of 8354")
	)
	(layers
		(0 "F.Cu" signal "TOP")
		(4 "In1.Cu" signal "GND")
		(6 "In2.Cu" signal "IN1")
		(8 "In3.Cu" signal "GND1")
		(10 "In4.Cu" signal "IN2")
		(12 "In5.Cu" signal "GND2")
		(14 "In6.Cu" signal "IN3")
		(16 "In7.Cu" signal "GND3")
		(18 "In8.Cu" signal "VCC")
		(20 "In9.Cu" signal "VCC1")
		(22 "In10.Cu" signal "GND4")
		(24 "In11.Cu" signal "IN4")
		(26 "In12.Cu" signal "GND5")
		(28 "In13.Cu" signal "IN5")
		(30 "In14.Cu" signal "GND6")
		(32 "In15.Cu" signal "IN6")
		(34 "In16.Cu" signal "GND7")
		(2 "B.Cu" signal "BOTTOM")
		(9 "F.Adhes" user "F.Adhesive")
		(11 "B.Adhes" user "B.Adhesive")
		(13 "F.Paste" user "Package Geometry/Pastemask Top")
		(15 "B.Paste" user "Package Geometry/Pastemask Bottom")
		(5 "F.SilkS" user "Ref Des/Silkscreen Top")
		(7 "B.SilkS" user "Ref Des/Silkscreen Bottom")
		(1 "F.Mask" user "Board Geometry/Soldermask Top")
		(3 "B.Mask" user "Board Geometry/Soldermask Bottom")
		(17 "Dwgs.User" user "User.Drawings")
		(19 "Cmts.User" user "User.Comments")
		(21 "Eco1.User" user "User.Eco1")
		(23 "Eco2.User" user "User.Eco2")
		(25 "Edge.Cuts" user "Board Geometry/Outline")
		(27 "Margin" user)
		(31 "F.CrtYd" user "Package Geometry/Place Bound Top")
		(29 "B.CrtYd" user "Package Geometry/Place Bound Bottom")
		(35 "F.Fab" user "Ref Des/Assembly Top")
		(33 "B.Fab" user "Ref Des/Assembly Bottom")
	)
	(footprint ""
		(layer "B.Cu")
		(at 386.350256 -182.867554 -90)
		(property "Reference" "PC559_4"
			(at 0 0 90)
			(layer "B.SilkS")
			(hide yes)
			(effects
				(font
					(size 1.27 1.27)
				)
				(justify mirror)
			)
		)
		(property "Value" ""
			(at 0 0 90)
			(layer "B.Fab")
			(effects
				(font
					(size 1.27 1.27)
				)
				(justify mirror)
			)
		)
		(duplicate_pad_numbers_are_jumpers no)
		(fp_line
			(start -1.524 0.762)
			(end 1.524 0.762)
			(stroke
				(width 0.1524)
				(type default)
			)
			(layer "B.SilkS")
		)
		(fp_line
			(start 1.524 0.762)
			(end 1.524 -0.762)
			(stroke
				(width 0.1524)
				(type default)
			)
			(layer "B.SilkS")
		)
		(fp_line
			(start -1.524 -0.762)
			(end -1.524 0.762)
			(stroke
				(width 0.1524)
				(type default)
			)
			(layer "B.SilkS")
		)
		(fp_line
			(start 1.524 -0.762)
			(end -1.524 -0.762)
			(stroke
				(width 0.1524)
				(type default)
			)
			(layer "B.SilkS")
		)
		(fp_line
			(start -1.1049 0.724916)
			(end -1.1049 -0.724916)
			(stroke
				(width 0.1)
				(type default)
			)
			(layer "B.Fab")
		)
		(fp_line
			(start 1.1049 0.724916)
			(end -1.1049 0.724916)
			(stroke
				(width 0.1)
				(type default)
			)
			(layer "B.Fab")
		)
		(fp_line
			(start -1.1049 -0.724916)
			(end 1.1049 -0.724916)
			(stroke
				(width 0.1)
				(type default)
			)
			(layer "B.Fab")
		)
		(fp_line
			(start 1.1049 -0.724916)
			(end 1.1049 0.724916)
			(stroke
				(width 0.1)
				(type default)
			)
			(layer "B.Fab")
		)
		(pad "1" smd rect
			(at 0.889 0 270)
			(size 1.016 1.27)
			(layers "B.Cu" "B.Mask" "B.Paste")
			(net "SW_P12V_AUX_PVDDCR_CPU0_P0_FLT")
		)
		(pad "2" smd rect
			(at -0.889 0 270)
			(size 1.016 1.27)
			(layers "B.Cu" "B.Mask" "B.Paste")
			(net "GND")
		)
	)
	(footprint ""
		(layer "B.Cu")
		(at 99.128834 -250.892564 180)
		(property "Reference" "C2669"
			(at 0 0 0)
			(layer "B.SilkS")
			(hide yes)
			(effects
				(font
					(size 1.27 1.27)
				)
				(justify mirror)
			)
		)
		(property "Value" ""
			(at 0 0 0)
			(layer "B.Fab")
			(effects
				(font
					(size 1.27 1.27)
				)
				(justify mirror)
			)
		)
		(duplicate_pad_numbers_are_jumpers no)
		(fp_line
			(start 0.7874 0.4064)
			(end 0.7874 -0.4064)
			(stroke
				(width 0.1524)
				(type default)
			)
			(layer "B.SilkS")
		)
		(fp_line
			(start 0.7874 -0.4064)
			(end -0.7874 -0.4064)
			(stroke
				(width 0.1524)
				(type default)
			)
			(layer "B.SilkS")
		)
		(fp_line
			(start -0.7874 0.4064)
			(end 0.7874 0.4064)
			(stroke
				(width 0.1524)
				(type default)
			)
			(layer "B.SilkS")
		)
		(fp_line
			(start -0.7874 -0.4064)
			(end -0.7874 0.4064)
			(stroke
				(width 0.1524)
				(type default)
			)
			(layer "B.SilkS")
		)
		(fp_line
			(start 0.67945 0.3048)
			(end 0.67945 -0.305054)
			(stroke
				(width 0.1)
				(type default)
			)
			(layer "B.Fab")
		)
		(fp_line
			(start 0.67945 -0.305054)
			(end 0.12065 -0.305054)
			(stroke
				(width 0.1)
				(type default)
			)
			(layer "B.Fab")
		)
		(fp_line
			(start 0.12065 0.3048)
			(end 0.67945 0.3048)
			(stroke
				(width 0.1)
				(type default)
			)
			(layer "B.Fab")
		)
		(fp_line
			(start 0.12065 0.2794)
			(end 0.12065 0.3048)
			(stroke
				(width 0.1)
				(type default)
			)
			(layer "B.Fab")
		)
		(fp_line
			(start 0.12065 -0.2794)
			(end -0.12065 -0.2794)
			(stroke
				(width 0.1)
				(type default)
			)
			(layer "B.Fab")
		)
		(fp_line
			(start 0.12065 -0.305054)
			(end 0.12065 -0.2794)
			(stroke
				(width 0.1)
				(type default)
			)
			(layer "B.Fab")
		)
		(fp_line
			(start -0.120396 0.3048)
			(end -0.120396 0.2794)
			(stroke
				(width 0.1)
				(type default)
			)
			(layer "B.Fab")
		)
		(fp_line
			(start -0.120396 0.2794)
			(end 0.12065 0.2794)
			(stroke
				(width 0.1)
				(type default)
			)
			(layer "B.Fab")
		)
		(fp_line
			(start -0.12065 -0.2794)
			(end -0.12065 -0.3048)
			(stroke
				(width 0.1)
				(type default)
			)
			(layer "B.Fab")
		)
		(fp_line
			(start -0.12065 -0.3048)
			(end -0.67945 -0.3048)
			(stroke
				(width 0.1)
				(type default)
			)
			(layer "B.Fab")
		)
		(fp_line
			(start -0.67945 0.3048)
			(end -0.120396 0.3048)
			(stroke
				(width 0.1)
				(type default)
			)
			(layer "B.Fab")
		)
		(fp_line
			(start -0.67945 -0.3048)
			(end -0.67945 0.3048)
			(stroke
				(width 0.1)
				(type default)
			)
			(layer "B.Fab")
		)
		(pad "1" smd circle
			(at 0.40005 0)
			(size 0 0)
			(layers "B.Cu" "B.Mask" "B.Paste")
			(net "PVDD18_S5_P1")
		)
		(pad "2" smd circle
			(at -0.40005 0)
			(size 0 0)
			(layers "B.Cu" "B.Mask" "B.Paste")
			(net "GND")
		)
	)
	(footprint ""
		(layer "B.Cu")
		(at 98.464878 -139.93241 90)
		(property "Reference" "PC11"
			(at 0 0 90)
			(layer "B.SilkS")
			(hide yes)
			(effects
				(font
					(size 1.27 1.27)
				)
				(justify mirror)
			)
		)
		(property "Value" ""
			(at 0 0 90)
			(layer "B.Fab")
			(effects
				(font
					(size 1.27 1.27)
				)
				(justify mirror)
			)
		)
		(duplicate_pad_numbers_are_jumpers no)
		(fp_line
			(start 0.7874 -0.4064)
			(end -0.7874 -0.4064)
			(stroke
				(width 0.1524)
				(type default)
			)
			(layer "B.SilkS")
		)
		(fp_line
			(start -0.7874 -0.4064)
			(end -0.7874 0.4064)
			(stroke
				(width 0.1524)
				(type default)
			)
			(layer "B.SilkS")
		)
		(fp_line
			(start 0.7874 0.4064)
			(end 0.7874 -0.4064)
			(stroke
				(width 0.1524)
				(type default)
			)
			(layer "B.SilkS")
		)
		(fp_line
			(start -0.7874 0.4064)
			(end 0.7874 0.4064)
			(stroke
				(width 0.1524)
				(type default)
			)
			(layer "B.SilkS")
		)
		(fp_line
			(start 0.67945 -0.305054)
			(end 0.12065 -0.305054)
			(stroke
				(width 0.1)
				(type default)
			)
			(layer "B.Fab")
		)
		(fp_line
			(start 0.12065 -0.305054)
			(end 0.12065 -0.2794)
			(stroke
				(width 0.1)
				(type default)
			)
			(layer "B.Fab")
		)
		(fp_line
			(start -0.12065 -0.3048)
			(end -0.67945 -0.3048)
			(stroke
				(width 0.1)
				(type default)
			)
			(layer "B.Fab")
		)
		(fp_line
			(start -0.67945 -0.3048)
			(end -0.67945 0.3048)
			(stroke
				(width 0.1)
				(type default)
			)
			(layer "B.Fab")
		)
		(fp_line
			(start 0.12065 -0.2794)
			(end -0.12065 -0.2794)
			(stroke
				(width 0.1)
				(type default)
			)
			(layer "B.Fab")
		)
		(fp_line
			(start -0.12065 -0.2794)
			(end -0.12065 -0.3048)
			(stroke
				(width 0.1)
				(type default)
			)
			(layer "B.Fab")
		)
		(fp_line
			(start 0.12065 0.2794)
			(end 0.12065 0.3048)
			(stroke
				(width 0.1)
				(type default)
			)
			(layer "B.Fab")
		)
		(fp_line
			(start -0.120396 0.2794)
			(end 0.12065 0.2794)
			(stroke
				(width 0.1)
				(type default)
			)
			(layer "B.Fab")
		)
		(fp_line
			(start 0.67945 0.3048)
			(end 0.67945 -0.305054)
			(stroke
				(width 0.1)
				(type default)
			)
			(layer "B.Fab")
		)
		(fp_line
			(start 0.12065 0.3048)
			(end 0.67945 0.3048)
			(stroke
				(width 0.1)
				(type default)
			)
			(layer "B.Fab")
		)
		(fp_line
			(start -0.120396 0.3048)
			(end -0.120396 0.2794)
			(stroke
				(width 0.1)
				(type default)
			)
			(layer "B.Fab")
		)
		(fp_line
			(start -0.67945 0.3048)
			(end -0.120396 0.3048)
			(stroke
				(width 0.1)
				(type default)
			)
			(layer "B.Fab")
		)
		(pad "1" smd circle
			(at 0.40005 0 270)
			(size 0 0)
			(layers "B.Cu" "B.Mask" "B.Paste")
			(net "PVDDCR_CPU0_P1_VCCS")
		)
		(pad "2" smd circle
			(at -0.40005 0 270)
			(size 0 0)
			(layers "B.Cu" "B.Mask" "B.Paste")
			(net "GND")
		)
	)
)
